# T6G (Grand Teton) — schematic netlist excerpt (pin names and nets, part order shuffled) for the footprints in the layout excerpt that follows; sources: Cadence DE-HDL packaged netlist, KiCad conversion of 04192023_DAF0TMB3IC0_F0TG_MB_C_brd_V02_OCP.brd

U105  PI3CSW12ZUAEX  IC  pkg UQFN10_0-5_2X1-5  page 159
  \1d+\  = I3C_0_SPD_DDRAF_CPU0_SCL
  \1d-\  = I3C_0_SPD_DDRAF_CPU0_SDA
  \2d+\  = I3C_SCM_0_R_SCL
  \2d-\  = I3C_SCM_0_R_SDA
  GND  = GND
  \oe#\  = FM_I3C_CPU0_MUX0_OE_N
  \d-\  = I3C_SPD_DDRAF_CPU0_LVC1_SDA
  \d+\  = I3C_SPD_DDRAF_CPU0_LVC1_SCL
  S  = FM_I3C_CPU0_MUX0_SEL
  VDD  = P3V3_AUX

(kicad_pcb
	(version 20260206)
	(generator "pcbnew")
	(generator_version "10.0")
	(general
		(thickness 1.6)
		(legacy_teardrops no)
	)
	(paper "A4")
	(title_block
		(title "04192023_DAF0TMB3IC0_F0TG_MB_C_brd_V02_OCP.brd")
		(comment 1 "Grand Teton / footprints 3702-3702 of 8354")
	)
	(layers
		(0 "F.Cu" signal "TOP")
		(4 "In1.Cu" signal "GND")
		(6 "In2.Cu" signal "IN1")
		(8 "In3.Cu" signal "GND1")
		(10 "In4.Cu" signal "IN2")
		(12 "In5.Cu" signal "GND2")
		(14 "In6.Cu" signal "IN3")
		(16 "In7.Cu" signal "GND3")
		(18 "In8.Cu" signal "VCC")
		(20 "In9.Cu" signal "VCC1")
		(22 "In10.Cu" signal "GND4")
		(24 "In11.Cu" signal "IN4")
		(26 "In12.Cu" signal "GND5")
		(28 "In13.Cu" signal "IN5")
		(30 "In14.Cu" signal "GND6")
		(32 "In15.Cu" signal "IN6")
		(34 "In16.Cu" signal "GND7")
		(2 "B.Cu" signal "BOTTOM")
		(9 "F.Adhes" user "F.Adhesive")
		(11 "B.Adhes" user "B.Adhesive")
		(13 "F.Paste" user "Package Geometry/Pastemask Top")
		(15 "B.Paste" user "Package Geometry/Pastemask Bottom")
		(5 "F.SilkS" user "Ref Des/Silkscreen Top")
		(7 "B.SilkS" user "Ref Des/Silkscreen Bottom")
		(1 "F.Mask" user "Board Geometry/Soldermask Top")
		(3 "B.Mask" user "Board Geometry/Soldermask Bottom")
		(17 "Dwgs.User" user "User.Drawings")
		(19 "Cmts.User" user "User.Comments")
		(21 "Eco1.User" user "User.Eco1")
		(23 "Eco2.User" user "User.Eco2")
		(25 "Edge.Cuts" user "Board Geometry/Outline")
		(27 "Margin" user)
		(31 "F.CrtYd" user "Package Geometry/Place Bound Top")
		(29 "B.CrtYd" user "Package Geometry/Place Bound Bottom")
		(35 "F.Fab" user "Ref Des/Assembly Top")
		(33 "B.Fab" user "Ref Des/Assembly Bottom")
	)
	(footprint ""
		(layer "F.Cu")
		(at 301.800768 -147.909788 180)
		(property "Reference" "U105"
			(at -1.93294 -3.065272 90)
			(unlocked yes)
			(layer "F.SilkS")
			(effects
				(font
					(size 0.7874 0.5842)
					(thickness 0.1524)
				)
			)
		)
		(property "Value" ""
			(at 0 0 180)
			(layer "F.Fab")
			(effects
				(font
					(size 1.27 1.27)
				)
			)
		)
		(duplicate_pad_numbers_are_jumpers no)
		(fp_line
			(start 1.03378 1.284478)
			(end -1.03378 1.284478)
			(stroke
				(width 0.1524)
				(type default)
			)
			(layer "F.SilkS")
		)
		(fp_line
			(start 1.03378 -1.284478)
			(end 1.03378 1.284478)
			(stroke
				(width 0.1524)
				(type default)
			)
			(layer "F.SilkS")
		)
		(fp_line
			(start -1.03378 1.284478)
			(end -1.03378 -1.284478)
			(stroke
				(width 0.1524)
				(type default)
			)
			(layer "F.SilkS")
		)
		(fp_line
			(start -1.03378 -1.284478)
			(end 1.03378 -1.284478)
			(stroke
				(width 0.1524)
				(type default)
			)
			(layer "F.SilkS")
		)
		(fp_poly
			(pts
				(xy -1.806702 -1.052576) (xy -1.201674 -0.750062) (xy -1.806702 -0.447548)
			)
			(stroke
				(width 0)
				(type default)
			)
			(fill yes)
			(layer "F.SilkS")
		)
		(fp_line
			(start 0.774954 1.02489)
			(end -0.774954 1.02489)
			(stroke
				(width 0.1)
				(type default)
			)
			(layer "F.Fab")
		)
		(fp_line
			(start 0.774954 -1.02489)
			(end 0.774954 1.02489)
			(stroke
				(width 0.1)
				(type default)
			)
			(layer "F.Fab")
		)
		(fp_line
			(start -0.774954 1.02489)
			(end -0.774954 -1.02489)
			(stroke
				(width 0.1)
				(type default)
			)
			(layer "F.Fab")
		)
		(fp_line
			(start -0.774954 -1.02489)
			(end 0.774954 -1.02489)
			(stroke
				(width 0.1)
				(type default)
			)
			(layer "F.Fab")
		)
		(fp_poly
			(pts
				(xy -1.201674 -0.750062) (xy -1.806702 -0.447548) (xy -1.806702 -1.052576)
			)
			(stroke
				(width 0)
				(type default)
			)
			(fill yes)
			(layer "F.Fab")
		)
		(pad "1" smd rect
			(at -0.64008 -0.750062 270)
			(size 0.3048 0.5334)
			(layers "F.Cu" "F.Mask" "F.Paste")
			(net "I3C_0_SPD_DDRAF_CPU0_SCL")
		)
		(pad "2" smd rect
			(at -0.64008 -0.249936 270)
			(size 0.254 0.5334)
			(layers "F.Cu" "F.Mask" "F.Paste")
			(net "I3C_0_SPD_DDRAF_CPU0_SDA")
		)
		(pad "3" smd rect
			(at -0.64008 0.249936 270)
			(size 0.254 0.5334)
			(layers "F.Cu" "F.Mask" "F.Paste")
			(net "I3C_SCM_0_R_SCL")
		)
		(pad "4" smd rect
			(at -0.64008 0.750062 270)
			(size 0.3048 0.5334)
			(layers "F.Cu" "F.Mask" "F.Paste")
			(net "I3C_SCM_0_R_SDA")
		)
		(pad "5" smd rect
			(at 0 0.839978 180)
			(size 0.3302 0.635)
			(layers "F.Cu" "F.Mask" "F.Paste")
			(net "GND")
		)
		(pad "6" smd rect
			(at 0.64008 0.750062 270)
			(size 0.3048 0.5334)
			(layers "F.Cu" "F.Mask" "F.Paste")
			(net "FM_I3C_CPU0_MUX0_OE_N")
		)
		(pad "7" smd rect
			(at 0.64008 0.249936 270)
			(size 0.254 0.5334)
			(layers "F.Cu" "F.Mask" "F.Paste")
			(net "I3C_SPD_DDRAF_CPU0_LVC1_SDA")
		)
		(pad "8" smd rect
			(at 0.64008 -0.249936 270)
			(size 0.254 0.5334)
			(layers "F.Cu" "F.Mask" "F.Paste")
			(net "I3C_SPD_DDRAF_CPU0_LVC1_SCL")
		)
		(pad "9" smd rect
			(at 0.64008 -0.750062 270)
			(size 0.3048 0.5334)
			(layers "F.Cu" "F.Mask" "F.Paste")
			(net "FM_I3C_CPU0_MUX0_SEL")
		)
		(pad "10" smd rect
			(at 0 -0.839978 180)
			(size 0.3302 0.635)
			(layers "F.Cu" "F.Mask" "F.Paste")
			(net "P3V3_AUX")
		)
	)
)
